FILE_TYPE = CONNECTIVITY;
{Allegro Design Entry HDL 17.2-2016 S081 (4005846) 1/11/2022}
"PAGE_NUMBER" = 198;
0"NC";
1"CLK_100M_CK440_PCH_EXTCLK_DP"CDS_PHYS_NET_NAME"CLK_100M_CK440_PCH_EXTCLK_DP";
2"CLK_100M_CK440_PCH_EXTCLK_DN"CDS_PHYS_NET_NAME"CLK_100M_CK440_PCH_EXTCLK_DN";
3"CLK_100M_CK440_PCH_EXTCLK_R_DP"CDS_PHYS_NET_NAME"CLK_100M_CK440_PCH_EXTCLK_R_DP";
4"CLK_100M_CK440_PCH_EXTCLK_R_DN"CDS_PHYS_NET_NAME"CLK_100M_CK440_PCH_EXTCLK_R_DN";
5"CLK_100M_OCP_SFF_1_DN"CDS_PHYS_NET_NAME"CLK_100M_OCP_SFF_1_DN";
6"CLK_100M_OCP_SFF_0_DN"CDS_PHYS_NET_NAME"CLK_100M_OCP_SFF_0_DN";
7"CLK_100M_OCP_SFF_0_DP"CDS_PHYS_NET_NAME"CLK_100M_OCP_SFF_0_DP";
8"CLK_100M_OCP_SFF_1_DP"CDS_PHYS_NET_NAME"CLK_100M_OCP_SFF_1_DP";
9"CLK_100M_OCP_SFF_2_DP"CDS_PHYS_NET_NAME"CLK_100M_OCP_SFF_2_DP";
10"CLK_100M_OCP_SFF_2_DN"CDS_PHYS_NET_NAME"CLK_100M_OCP_SFF_2_DN";
11"CLK_100M_OCP_SFF_1_R_DP"CDS_PHYS_NET_NAME"CLK_100M_OCP_SFF_1_R_DP";
12"CLK_100M_OCP_SFF_2_R_DN"CDS_PHYS_NET_NAME"CLK_100M_OCP_SFF_2_R_DN";
13"CLK_100M_OCP_SFF_0_R_DP"CDS_PHYS_NET_NAME"CLK_100M_OCP_SFF_0_R_DP";
14"CLK_100M_OCP_SFF_1_R_DN"CDS_PHYS_NET_NAME"CLK_100M_OCP_SFF_1_R_DN";
15"CLK_100M_OCP_SFF_2_R_DP"CDS_PHYS_NET_NAME"CLK_100M_OCP_SFF_2_R_DP";
16"CLK_100M_OCP_SFF_0_R_DN"CDS_PHYS_NET_NAME"CLK_100M_OCP_SFF_0_R_DN";
17"CLK_25M_NSSC_CPU0_DP";
18"CLK_25M_NSSC_CPU0_DN";
19"CLK_100M_OCP_SFF_3_DN"CDS_PHYS_NET_NAME"CLK_100M_OCP_SFF_3_DN";
20"CLK_100M_OCP_SFF_3_DP"CDS_PHYS_NET_NAME"CLK_100M_OCP_SFF_3_DP";
21"CLK_25M_NSSC_CPU1_DP";
22"CLK_25M_NSSC_CPU1_DN";
23"CLK_25M_PCH_REF_NS_DN";
24"CLK_25M_CK440_CPU1_R_DN";
25"CLK_25M_PCH_REF_NS_DP";
26"CLK_25M_CK440_CPU0_R_DP";
27"CLK_25M_CK440_CPU1_R_DP";
28"CLK_25M_CK440_CPU0_R_DN";
29"CLK_100M_OCP_SFF_3_R_DP"CDS_PHYS_NET_NAME"CLK_100M_OCP_SFF_3_R_DP";
30"CLK_25M_PCH_CPU0_DP";
31"CLK_25M_CK440_CPU0_DN";
32"CLK_25M_PCH_CPU0_DN";
33"CLK_25M_CK440_CPU0_DP";
34"CLK_100M_OCP_SFF_3_R_DN"CDS_PHYS_NET_NAME"CLK_100M_OCP_SFF_3_R_DN";
35"CLK_25M_CK440_ISCLK_REF_DN";
36"CLK_25M_CK440_CPU1_DP";
37"CLK_25M_PCH_CPU1_DP";
38"CLK_25M_CK440_CPU1_DN";
39"CLK_25M_PCH_CPU1_DN";
40"CLK_25M_CK440_ISCLK_REF_DP";
%"Q_RES"
"1","(-6100,-2725)","0","pure_quanta","I10";
;
PART_NUMBER"CS00002JB13"
PACK_TYPE"0402LF"
VALUE"0"
TOLERANCE"5%"
MATERIAL"CHIP"
WATTAGE"1/16W"
$LOCATION"R1018"
CDS_LIB"pure_quanta"
CDS_LOCATION"R1018"
$SEC"1"
CDS_SEC"1";
"B"
$PN"2"24;
"A"
$PN"1"38;
%"Q_RES"
"1","(-6100,-2550)","0","pure_quanta","I11";
;
PART_NUMBER"CS00002JB13"
MATERIAL"EMPTY"
VALUE"0"
TOLERANCE"5%"
PACK_TYPE"0402LF"
WATTAGE"1/16W"
$LOCATION"R1017"
CDS_LIB"pure_quanta"
CDS_LOCATION"R1017"
$SEC"1"
CDS_SEC"1";
"B"
$PN"2"21;
"A"
$PN"1"37;
%"Q_RES"
"1","(-6100,-2375)","0","pure_quanta","I12";
;
PART_NUMBER"CS00002JB13"
WATTAGE"1/16W"
PACK_TYPE"0402LF"
MATERIAL"CHIP"
TOLERANCE"5%"
VALUE"0"
$LOCATION"R1016"
CDS_LIB"pure_quanta"
CDS_LOCATION"R1016"
$SEC"1"
CDS_SEC"1";
"B"
$PN"2"27;
"A"
$PN"1"36;
%"Q_RES"
"1","(-6100,-1600)","0","pure_quanta","I19";
;
PART_NUMBER"CS00002JB13"
PACK_TYPE"0402LF"
WATTAGE"1/16W"
VALUE"0"
TOLERANCE"5%"
MATERIAL"EMPTY"
$LOCATION"R1015"
CDS_LIB"pure_quanta"
CDS_LOCATION"R1015"
$SEC"1"
CDS_SEC"1";
"B"
$PN"2"18;
"A"
$PN"1"32;
%"Q_RES"
"1","(-6100,-1425)","0","pure_quanta","I20";
;
PART_NUMBER"CS00002JB13"
VALUE"0"
TOLERANCE"5%"
MATERIAL"CHIP"
WATTAGE"1/16W"
PACK_TYPE"0402LF"
$LOCATION"R1014"
CDS_LIB"pure_quanta"
CDS_LOCATION"R1014"
$SEC"1"
CDS_SEC"1";
"B"
$PN"2"28;
"A"
$PN"1"31;
%"Q_RES"
"1","(-6100,-1250)","0","pure_quanta","I21";
;
PART_NUMBER"CS00002JB13"
VALUE"0"
WATTAGE"1/16W"
PACK_TYPE"0402LF"
TOLERANCE"5%"
MATERIAL"EMPTY"
$LOCATION"R1013"
CDS_LIB"pure_quanta"
CDS_LOCATION"R1013"
$SEC"1"
CDS_SEC"1";
"B"
$PN"2"17;
"A"
$PN"1"30;
%"Q_RES"
"1","(-6100,-1075)","0","pure_quanta","I22";
;
PART_NUMBER"CS00002JB13"
TOLERANCE"5%"
MATERIAL"CHIP"
VALUE"0"
PACK_TYPE"0402LF"
WATTAGE"1/16W"
$LOCATION"R1012"
CDS_LIB"pure_quanta"
CDS_LOCATION"R1012"
$SEC"1"
CDS_SEC"1";
"B"
$PN"2"26;
"A"
$PN"1"33;
%"Q_RES"
"1","(-6025,-350)","0","pure_quanta","I23";
;
PART_NUMBER"CS02202FB02"
PACK_TYPE"0402LF"
TOLERANCE"1%"
WATTAGE"1/16W"
VALUE"22"
MATERIAL"CHIP"
$LOCATION"R1276"
CDS_LIB"pure_quanta"
CDS_LOCATION"R1276"
$SEC"1"
CDS_SEC"1";
"B"
$PN"2"19;
"A"
$PN"1"34;
%"Q_RES"
"1","(-6025,-200)","0","pure_quanta","I24";
;
PART_NUMBER"CS02202FB02"
MATERIAL"CHIP"
PACK_TYPE"0402LF"
TOLERANCE"1%"
WATTAGE"1/16W"
VALUE"22"
$LOCATION"R1275"
CDS_LIB"pure_quanta"
CDS_LOCATION"R1275"
$SEC"1"
CDS_SEC"1";
"B"
$PN"2"20;
"A"
$PN"1"29;
%"Q_RES"
"1","(-4375,-2725)","0","pure_quanta","I27";
;
PART_NUMBER"CS00002JB13"
TOLERANCE"5%"
VALUE"0"
MATERIAL"CHIP"
WATTAGE"1/16W"
PACK_TYPE"0402LF"
$LOCATION"R1023"
CDS_LIB"pure_quanta"
CDS_LOCATION"R1023"
$SEC"1"
CDS_SEC"1";
"B"
$PN"2"22;
"A"
$PN"1"24;
%"Q_RES"
"1","(-4375,-2375)","0","pure_quanta","I28";
;
PART_NUMBER"CS00002JB13"
WATTAGE"1/16W"
VALUE"0"
TOLERANCE"5%"
MATERIAL"CHIP"
PACK_TYPE"0402LF"
$LOCATION"R1022"
CDS_LIB"pure_quanta"
CDS_LOCATION"R1022"
$SEC"1"
CDS_SEC"1";
"B"
$PN"2"21;
"A"
$PN"1"27;
%"Q_RES"
"1","(-4375,-1425)","0","pure_quanta","I29";
;
PART_NUMBER"CS00002JB13"
TOLERANCE"5%"
VALUE"0"
MATERIAL"CHIP"
PACK_TYPE"0402LF"
WATTAGE"1/16W"
$LOCATION"R1021"
CDS_LIB"pure_quanta"
CDS_LOCATION"R1021"
$SEC"1"
CDS_SEC"1";
"B"
$PN"2"18;
"A"
$PN"1"28;
%"Q_RES"
"1","(-4375,-1075)","0","pure_quanta","I30";
;
PART_NUMBER"CS00002JB13"
WATTAGE"1/16W"
PACK_TYPE"0402LF"
MATERIAL"CHIP"
TOLERANCE"5%"
VALUE"0"
$LOCATION"R1020"
CDS_LIB"pure_quanta"
CDS_LOCATION"R1020"
$SEC"1"
CDS_SEC"1";
"B"
$PN"2"17;
"A"
$PN"1"26;
%"Q_RES"
"1","(-6025,50)","0","pure_quanta","I43";
;
PART_NUMBER"CS02202FB02"
TOLERANCE"1%"
PACK_TYPE"0402LF"
WATTAGE"1/16W"
MATERIAL"CHIP"
VALUE"22"
$LOCATION"R1274"
CDS_LIB"pure_quanta"
CDS_LOCATION"R1274"
$SEC"1"
CDS_SEC"1";
"B"
$PN"2"10;
"A"
$PN"1"12;
%"Q_RES"
"1","(-6025,200)","0","pure_quanta","I44";
;
PART_NUMBER"CS02202FB02"
WATTAGE"1/16W"
MATERIAL"CHIP"
PACK_TYPE"0402LF"
TOLERANCE"1%"
VALUE"22"
$LOCATION"R1273"
CDS_LIB"pure_quanta"
CDS_LOCATION"R1273"
$SEC"1"
CDS_SEC"1";
"B"
$PN"2"9;
"A"
$PN"1"15;
%"Q_RES"
"1","(-6025,450)","0","pure_quanta","I45";
;
PART_NUMBER"CS02202FB02"
TOLERANCE"1%"
VALUE"22"
WATTAGE"1/16W"
MATERIAL"CHIP"
PACK_TYPE"0402LF"
$LOCATION"R566"
CDS_LIB"pure_quanta"
CDS_LOCATION"R566"
$SEC"1"
CDS_SEC"1";
"B"
$PN"2"5;
"A"
$PN"1"14;
%"Q_RES"
"1","(-6025,600)","0","pure_quanta","I46";
;
PART_NUMBER"CS02202FB02"
MATERIAL"CHIP"
PACK_TYPE"0402LF"
VALUE"22"
TOLERANCE"1%"
WATTAGE"1/16W"
$LOCATION"R565"
CDS_LIB"pure_quanta"
CDS_LOCATION"R565"
$SEC"1"
CDS_SEC"1";
"B"
$PN"2"8;
"A"
$PN"1"11;
%"Q_RES"
"1","(-6025,850)","0","pure_quanta","I47";
;
PART_NUMBER"CS02202FB02"
PACK_TYPE"0402LF"
WATTAGE"1/16W"
VALUE"22"
TOLERANCE"1%"
MATERIAL"CHIP"
$LOCATION"R564"
CDS_LIB"pure_quanta"
CDS_LOCATION"R564"
$SEC"1"
CDS_SEC"1";
"B"
$PN"2"6;
"A"
$PN"1"16;
%"Q_RES"
"1","(-6025,1000)","0","pure_quanta","I48";
;
PART_NUMBER"CS02202FB02"
PACK_TYPE"0402LF"
VALUE"22"
TOLERANCE"1%"
MATERIAL"CHIP"
WATTAGE"1/16W"
$LOCATION"R563"
CDS_LIB"pure_quanta"
CDS_LOCATION"R563"
$SEC"1"
CDS_SEC"1";
"B"
$PN"2"7;
"A"
$PN"1"13;
%"Q_RES"
"1","(-1675,850)","0","pure_quanta","I57";
;
PART_NUMBER"CS00002JB13"
PACK_TYPE"0402LF"
VALUE"0"
WATTAGE"1/16W"
TOLERANCE"5%"
MATERIAL"CHIP"
$LOCATION"R554"
CDS_LIB"pure_quanta"
CDS_LOCATION"R554"
$SEC"1"
CDS_SEC"1";
"B"
$PN"2"2;
"A"
$PN"1"4;
%"Q_RES"
"1","(-1675,1025)","0","pure_quanta","I58";
;
PART_NUMBER"CS00002JB13"
VALUE"0"
TOLERANCE"5%"
WATTAGE"1/16W"
PACK_TYPE"0402LF"
MATERIAL"CHIP"
$LOCATION"R553"
CDS_LIB"pure_quanta"
CDS_LOCATION"R553"
$SEC"1"
CDS_SEC"1";
"B"
$PN"2"1;
"A"
$PN"1"3;
%"Q_RES"
"1","(-6125,-3825)","0","pure_quanta","I7";
;
PART_NUMBER"CS00002JB13"
WATTAGE"1/16W"
PACK_TYPE"0402LF"
VALUE"0"
TOLERANCE"5%"
MATERIAL"CHIP"
$LOCATION"R1011"
CDS_LIB"pure_quanta"
CDS_LOCATION"R1011"
$SEC"1"
CDS_SEC"1";
"B"
$PN"2"23;
"A"
$PN"1"35;
%"Q_RES"
"1","(-6125,-3650)","0","pure_quanta","I8";
;
PART_NUMBER"CS00002JB13"
MATERIAL"CHIP"
VALUE"0"
WATTAGE"1/16W"
PACK_TYPE"0402LF"
TOLERANCE"5%"
$LOCATION"R1010"
CDS_LIB"pure_quanta"
CDS_LOCATION"R1010"
$SEC"1"
CDS_SEC"1";
"B"
$PN"2"25;
"A"
$PN"1"40;
%"Q_RES"
"1","(-6100,-2900)","0","pure_quanta","I9";
;
PART_NUMBER"CS00002JB13"
PACK_TYPE"0402LF"
WATTAGE"1/16W"
VALUE"0"
TOLERANCE"5%"
MATERIAL"EMPTY"
$LOCATION"R1019"
CDS_LIB"pure_quanta"
CDS_LOCATION"R1019"
$SEC"1"
CDS_SEC"1";
"B"
$PN"2"22;
"A"
$PN"1"39;
END.
